# T6G (Grand Teton) — schematic netlist excerpt (pin names and nets, part order shuffled) for the footprints in the layout excerpt that follows; sources: Cadence DE-HDL packaged netlist, KiCad conversion of 04192023_DAF0TMB3IC0_F0TG_MB_C_brd_V02_OCP.brd

C242  Q_CAP  1000PF 50V 5% X7R  pkg 0402  page 210 : A = PVDDCR_SOC_P1_EN_RC ; B = GND

(kicad_pcb
	(version 20260206)
	(generator "pcbnew")
	(generator_version "10.0")
	(general
		(thickness 1.6)
		(legacy_teardrops no)
	)
	(paper "A4")
	(title_block
		(title "04192023_DAF0TMB3IC0_F0TG_MB_C_brd_V02_OCP.brd")
		(comment 1 "Grand Teton / footprints 3183-3183 of 8354")
	)
	(layers
		(0 "F.Cu" signal "TOP")
		(4 "In1.Cu" signal "GND")
		(6 "In2.Cu" signal "IN1")
		(8 "In3.Cu" signal "GND1")
		(10 "In4.Cu" signal "IN2")
		(12 "In5.Cu" signal "GND2")
		(14 "In6.Cu" signal "IN3")
		(16 "In7.Cu" signal "GND3")
		(18 "In8.Cu" signal "VCC")
		(20 "In9.Cu" signal "VCC1")
		(22 "In10.Cu" signal "GND4")
		(24 "In11.Cu" signal "IN4")
		(26 "In12.Cu" signal "GND5")
		(28 "In13.Cu" signal "IN5")
		(30 "In14.Cu" signal "GND6")
		(32 "In15.Cu" signal "IN6")
		(34 "In16.Cu" signal "GND7")
		(2 "B.Cu" signal "BOTTOM")
		(9 "F.Adhes" user "F.Adhesive")
		(11 "B.Adhes" user "B.Adhesive")
		(13 "F.Paste" user "Package Geometry/Pastemask Top")
		(15 "B.Paste" user "Package Geometry/Pastemask Bottom")
		(5 "F.SilkS" user "Ref Des/Silkscreen Top")
		(7 "B.SilkS" user "Ref Des/Silkscreen Bottom")
		(1 "F.Mask" user "Board Geometry/Soldermask Top")
		(3 "B.Mask" user "Board Geometry/Soldermask Bottom")
		(17 "Dwgs.User" user "User.Drawings")
		(19 "Cmts.User" user "User.Comments")
		(21 "Eco1.User" user "User.Eco1")
		(23 "Eco2.User" user "User.Eco2")
		(25 "Edge.Cuts" user "Board Geometry/Outline")
		(27 "Margin" user)
		(31 "F.CrtYd" user "Package Geometry/Place Bound Top")
		(29 "B.CrtYd" user "Package Geometry/Place Bound Bottom")
		(35 "F.Fab" user "Ref Des/Assembly Top")
		(33 "B.Fab" user "Ref Des/Assembly Bottom")
	)
	(footprint ""
		(layer "F.Cu")
		(at 95.489522 -136.066784 -90)
		(property "Reference" "C242"
			(at 0 0 270)
			(layer "F.SilkS")
			(hide yes)
			(effects
				(font
					(size 1.27 1.27)
				)
			)
		)
		(property "Value" ""
			(at 0 0 270)
			(layer "F.Fab")
			(effects
				(font
					(size 1.27 1.27)
				)
			)
		)
		(duplicate_pad_numbers_are_jumpers no)
		(fp_line
			(start -0.7874 0.4064)
			(end -0.7874 -0.4064)
			(stroke
				(width 0.1524)
				(type default)
			)
			(layer "F.SilkS")
		)
		(fp_line
			(start 0.7874 0.4064)
			(end -0.7874 0.4064)
			(stroke
				(width 0.1524)
				(type default)
			)
			(layer "F.SilkS")
		)
		(fp_line
			(start -0.7874 -0.4064)
			(end 0.7874 -0.4064)
			(stroke
				(width 0.1524)
				(type default)
			)
			(layer "F.SilkS")
		)
		(fp_line
			(start 0.7874 -0.4064)
			(end 0.7874 0.4064)
			(stroke
				(width 0.1524)
				(type default)
			)
			(layer "F.SilkS")
		)
		(fp_line
			(start -0.67945 0.3048)
			(end -0.67945 -0.305054)
			(stroke
				(width 0.1)
				(type default)
			)
			(layer "F.Fab")
		)
		(fp_line
			(start -0.12065 0.3048)
			(end -0.67945 0.3048)
			(stroke
				(width 0.1)
				(type default)
			)
			(layer "F.Fab")
		)
		(fp_line
			(start 0.120396 0.3048)
			(end 0.120396 0.2794)
			(stroke
				(width 0.1)
				(type default)
			)
			(layer "F.Fab")
		)
		(fp_line
			(start 0.67945 0.3048)
			(end 0.120396 0.3048)
			(stroke
				(width 0.1)
				(type default)
			)
			(layer "F.Fab")
		)
		(fp_line
			(start -0.12065 0.2794)
			(end -0.12065 0.3048)
			(stroke
				(width 0.1)
				(type default)
			)
			(layer "F.Fab")
		)
		(fp_line
			(start 0.120396 0.2794)
			(end -0.12065 0.2794)
			(stroke
				(width 0.1)
				(type default)
			)
			(layer "F.Fab")
		)
		(fp_line
			(start -0.12065 -0.2794)
			(end 0.12065 -0.2794)
			(stroke
				(width 0.1)
				(type default)
			)
			(layer "F.Fab")
		)
		(fp_line
			(start 0.12065 -0.2794)
			(end 0.12065 -0.3048)
			(stroke
				(width 0.1)
				(type default)
			)
			(layer "F.Fab")
		)
		(fp_line
			(start 0.12065 -0.3048)
			(end 0.67945 -0.3048)
			(stroke
				(width 0.1)
				(type default)
			)
			(layer "F.Fab")
		)
		(fp_line
			(start 0.67945 -0.3048)
			(end 0.67945 0.3048)
			(stroke
				(width 0.1)
				(type default)
			)
			(layer "F.Fab")
		)
		(fp_line
			(start -0.67945 -0.305054)
			(end -0.12065 -0.305054)
			(stroke
				(width 0.1)
				(type default)
			)
			(layer "F.Fab")
		)
		(fp_line
			(start -0.12065 -0.305054)
			(end -0.12065 -0.2794)
			(stroke
				(width 0.1)
				(type default)
			)
			(layer "F.Fab")
		)
		(pad "1" smd circle
			(at -0.40005 0 270)
			(size 0 0)
			(layers "F.Cu" "F.Mask" "F.Paste")
			(net "PVDDCR_SOC_P1_EN_RC")
		)
		(pad "2" smd circle
			(at 0.40005 0 270)
			(size 0 0)
			(layers "F.Cu" "F.Mask" "F.Paste")
			(net "GND")
		)
	)
)
